#ISCELL
  mstr_misc dns *
  *
#ISCELL
  pure_quanta quanta_title_block_c *
  *
#ISCELL
  pure_quanta_power universal_gnd *
  page307_i14
#CELL
  pure_quanta q_res *
  page307_i15
#CELL
  pure_quanta q_cap *
  page307_i17
#ISCELL
  pure_quanta_power universal_gnd *
  page307_i18
#ISCELL
  pure_quanta_power universal_power *
  page307_i19
#ISCELL
  standard offpage *
  page307_i20
#ISCELL
  standard offpage *
  page307_i21
#ISCELL
  standard offpage *
  page307_i22
#ISCELL
  standard offpage *
  page307_i23
#ISCELL
  pure_quanta_power universal_gnd *
  page307_i24
#ISCELL
  pure_quanta_power universal_gnd *
  page307_i25
#ISCELL
  pure_quanta_power universal_power *
  page307_i26
#ISCELL
  standard offpage *
  page307_i27
#ISCELL
  standard offpage *
  page307_i28
#ISCELL
  standard offpage *
  page307_i29
#ISCELL
  standard offpage *
  page307_i3
#ISCELL
  standard offpage *
  page307_i30
#ISCELL
  pure_quanta_power universal_gnd *
  page307_i31
#CELL
  pure_quanta 74cbtlv3126pw *
  page307_i32
#CELL
  pure_quanta q_cap *
  page307_i33
#ISCELL
  pure_quanta_power universal_gnd *
  page307_i34
#ISCELL
  pure_quanta_power universal_power *
  page307_i35
#CELL
  pure_quanta q_res *
  page307_i37
#CELL
  pure_quanta q_res *
  page307_i38
#ISCELL
  pure_quanta_power universal_gnd *
  page307_i39
#CELL
  pure_quanta q_res *
  page307_i40
#ISCELL
  standard offpage *
  page307_i44
#ISCELL
  standard offpage *
  page307_i45
#ISCELL
  standard offpage *
  page307_i46
#CELL
  pure_quanta q_res *
  page307_i56
#CELL
  pure_quanta q_res *
  page307_i60
#CELL
  pure_quanta q_res *
  page307_i61
#CELL
  pure_quanta q_res *
  page307_i62
#CELL
  pure_quanta q_res *
  page307_i63
#CELL
  pure_quanta q_res *
  page307_i64
#CELL
  pure_quanta q_res *
  page307_i65
#ISCELL
  standard offpage *
  page307_i66
#ISCELL
  standard offpage *
  page307_i67
#ISCELL
  standard offpage *
  page307_i68
#ISCELL
  standard offpage *
  page307_i69
#ISCELL
  standard offpage *
  page307_i73
#ISCELL
  standard offpage *
  page307_i74
#ISCELL
  standard offpage *
  page307_i75
#ISCELL
  standard offpage *
  page307_i76
#CELL
  pure_quanta q_cap *
  page307_i77
#CELL
  pure_quanta 74cbtlv3126pw *
  page307_i78
#CELL
  pure_quanta q_res *
  page307_i79
#CELL
  pure_quanta 74lvc1g126se7 *
  page307_i80
#CELL
  pure_quanta q_res *
  page307_i81
#ISCELL
  standard offpage *
  page307_i82
#ISCELL
  pure_quanta_power universal_gnd *
  page307_i83
#ISCELL
  standard offpage *
  page307_i84
#CELL
  pure_quanta q_res *
  page307_i85
#CELL
  pure_quanta q_res *
  page307_i86
#ISCELL
  standard offpage *
  page307_i9
